# BASEBOARD_FAB2 (Tioga Pass) — schematic netlist excerpt (pin names and nets, part order shuffled) for the footprints in the layout excerpt that follows; sources: Cadence DE-HDL packaged netlist, KiCad conversion of Wiwynn_Tioga_Pass_MB.brd

R4D5  RES  27.4 1% CHIP  pkg 0402  page 103 : A = CLK_100M_CPU0_RC_REFCLK1_R_DN ; B = CLK_100M_CPU0_RC_REFCLK1_DN
C25W21  CAP_A  0.1UF 16V 10% X7R  pkg 0402V  page 145 : A = P2E_SSB_BMC_RX_DN ; B = P2E_SSB_BMC_RX_C_DN
C5G13  CAP_A  47UF 4V 20% X5R  pkg 0603V  page 217 : A = PVDDQ_ABC ; B = GND

(kicad_pcb
	(version 20260206)
	(generator "pcbnew")
	(generator_version "10.0")
	(general
		(thickness 1.6)
		(legacy_teardrops no)
	)
	(paper "A4")
	(title_block
		(title "Wiwynn_Tioga_Pass_MB.brd")
		(comment 1 "Tioga Pass / footprints 1165-1167 of 4770")
	)
	(layers
		(0 "F.Cu" signal "TOP")
		(4 "In1.Cu" signal "L2GND")
		(6 "In2.Cu" signal "L3")
		(8 "In3.Cu" signal "L4GND")
		(10 "In4.Cu" signal "L5")
		(12 "In5.Cu" signal "L6GND")
		(14 "In6.Cu" signal "L7VCC")
		(16 "In7.Cu" signal "L8VCC")
		(18 "In8.Cu" signal "L9GND")
		(20 "In9.Cu" signal "L10")
		(22 "In10.Cu" signal "L11GND")
		(24 "In11.Cu" signal "L12")
		(26 "In12.Cu" signal "L13GND")
		(2 "B.Cu" signal "BOTTOM")
		(9 "F.Adhes" user "F.Adhesive")
		(11 "B.Adhes" user "B.Adhesive")
		(13 "F.Paste" user "Package Geometry/Pastemask Top")
		(15 "B.Paste" user "Package Geometry/Pastemask Bottom")
		(5 "F.SilkS" user "Ref Des/Silkscreen Top")
		(7 "B.SilkS" user "Ref Des/Silkscreen Bottom")
		(1 "F.Mask" user "Board Geometry/Soldermask Top")
		(3 "B.Mask" user "Board Geometry/Soldermask Bottom")
		(17 "Dwgs.User" user "User.Drawings")
		(19 "Cmts.User" user "User.Comments")
		(21 "Eco1.User" user "User.Eco1")
		(23 "Eco2.User" user "User.Eco2")
		(25 "Edge.Cuts" user "Board Geometry/Outline")
		(27 "Margin" user)
		(31 "F.CrtYd" user "Package Geometry/Place Bound Top")
		(29 "B.CrtYd" user "Package Geometry/Place Bound Bottom")
		(35 "F.Fab" user "Ref Des/Assembly Top")
		(33 "B.Fab" user "Ref Des/Assembly Bottom")
	)
	(footprint ""
		(layer "F.Cu")
		(at 252.1585 -3.3528 -90)
		(property "Reference" "C5G13"
			(at 1.848866 0.752348 270)
			(unlocked yes)
			(layer "F.SilkS")
			(effects
				(font
					(size 1.27 0.9652)
					(thickness 0.1524)
				)
			)
		)
		(property "Value" ""
			(at 0 0 270)
			(layer "F.Fab")
			(effects
				(font
					(size 1.27 1.27)
				)
			)
		)
		(duplicate_pad_numbers_are_jumpers no)
		(fp_rect
			(start -0.500126 1.598422)
			(end 0.500126 -0.201422)
			(stroke
				(width 0)
				(type default)
			)
			(fill no)
			(layer "F.CrtYd")
		)
		(fp_line
			(start -0.500126 1.598422)
			(end -0.500126 -0.201422)
			(stroke
				(width 0.1)
				(type default)
			)
			(layer "F.Fab")
		)
		(fp_line
			(start 0.500126 1.598422)
			(end -0.500126 1.598422)
			(stroke
				(width 0.1)
				(type default)
			)
			(layer "F.Fab")
		)
		(fp_line
			(start -0.500126 -0.201422)
			(end 0.500126 -0.201422)
			(stroke
				(width 0.1)
				(type default)
			)
			(layer "F.Fab")
		)
		(fp_line
			(start 0.500126 -0.201422)
			(end 0.500126 1.598422)
			(stroke
				(width 0.1)
				(type default)
			)
			(layer "F.Fab")
		)
		(pad "1" smd rect
			(at 0 0 180)
			(size 0.889 0.9906)
			(layers "F.Cu" "F.Mask" "F.Paste")
			(net "PVDDQ_ABC")
		)
		(pad "2" smd rect
			(at 0 1.397 180)
			(size 0.889 0.9906)
			(layers "F.Cu" "F.Mask" "F.Paste")
			(net "GND")
		)
		(zone
			(layer "F.Cu")
			(hatch none 0.5)
			(connect_pads
				(clearance 0)
			)
			(min_thickness 0.25)
			(keepout
				(tracks allowed)
				(vias not_allowed)
				(pads allowed)
				(copperpour not_allowed)
				(footprints allowed)
			)
			(placement
				(enabled no)
				(sheetname "")
			)
			(fill
				(thermal_gap 0.5)
				(thermal_bridge_width 0.5)
				(island_removal_mode 0)
			)
			(polygon
				(pts
					(xy 251.206 -3.8481) (xy 251.206 -2.8575) (xy 251.714 -2.8575) (xy 251.714 -3.8481)
				)
			)
		)
		(zone
			(layer "F.Cu")
			(hatch none 0.5)
			(connect_pads
				(clearance 0)
			)
			(min_thickness 0.25)
			(keepout
				(tracks not_allowed)
				(vias allowed)
				(pads allowed)
				(copperpour not_allowed)
				(footprints allowed)
			)
			(placement
				(enabled no)
				(sheetname "")
			)
			(fill
				(thermal_gap 0.5)
				(thermal_bridge_width 0.5)
				(island_removal_mode 0)
			)
			(polygon
				(pts
					(xy 251.206 -3.8481) (xy 251.206 -2.8575) (xy 251.714 -2.8575) (xy 251.714 -3.8481)
				)
			)
		)
	)
	(footprint ""
		(layer "F.Cu")
		(at 414.126172 -48.083978 180)
		(property "Reference" "C25W21"
			(at -0.8382 -0.67818 180)
			(unlocked yes)
			(layer "F.SilkS")
			(effects
				(font
					(size 0.4064 0.254)
					(thickness 0.1524)
				)
				(justify left)
			)
		)
		(property "Value" ""
			(at 0 0 180)
			(layer "F.Fab")
			(effects
				(font
					(size 1.27 1.27)
				)
			)
		)
		(duplicate_pad_numbers_are_jumpers no)
		(fp_poly
			(pts
				(xy 0.3048 -0.1016) (xy 0.3048 0.9906) (xy -0.3048 0.9906) (xy -0.3048 -0.1016)
			)
			(stroke
				(width 0)
				(type default)
			)
			(fill no)
			(layer "F.CrtYd")
		)
		(fp_line
			(start 0.3048 0.9906)
			(end 0.3048 -0.1016)
			(stroke
				(width 0.1)
				(type default)
			)
			(layer "F.Fab")
		)
		(fp_line
			(start 0.3048 -0.1016)
			(end -0.3048 -0.1016)
			(stroke
				(width 0.1)
				(type default)
			)
			(layer "F.Fab")
		)
		(fp_line
			(start -0.3048 0.9906)
			(end 0.3048 0.9906)
			(stroke
				(width 0.1)
				(type default)
			)
			(layer "F.Fab")
		)
		(fp_line
			(start -0.3048 -0.1016)
			(end -0.3048 0.9906)
			(stroke
				(width 0.1)
				(type default)
			)
			(layer "F.Fab")
		)
		(pad "1" smd rect
			(at 0 0 180)
			(size 0.508 0.508)
			(layers "F.Cu" "F.Mask" "F.Paste")
			(net "P2E_SSB_BMC_RX_DN")
		)
		(pad "2" smd rect
			(at 0 0.889 180)
			(size 0.508 0.508)
			(layers "F.Cu" "F.Mask" "F.Paste")
			(net "P2E_SSB_BMC_RX_C_DN")
		)
		(zone
			(layer "F.Cu")
			(hatch none 0.5)
			(connect_pads
				(clearance 0)
			)
			(min_thickness 0.25)
			(keepout
				(tracks not_allowed)
				(vias allowed)
				(pads allowed)
				(copperpour not_allowed)
				(footprints allowed)
			)
			(placement
				(enabled no)
				(sheetname "")
			)
			(fill
				(thermal_gap 0.5)
				(thermal_bridge_width 0.5)
				(island_removal_mode 0)
			)
			(polygon
				(pts
					(xy 414.380172 -48.718978) (xy 413.872172 -48.718978) (xy 413.872172 -48.337978) (xy 414.380172 -48.337978)
				)
			)
		)
		(zone
			(layer "F.Cu")
			(hatch none 0.5)
			(connect_pads
				(clearance 0)
			)
			(min_thickness 0.25)
			(keepout
				(tracks allowed)
				(vias not_allowed)
				(pads allowed)
				(copperpour not_allowed)
				(footprints allowed)
			)
			(placement
				(enabled no)
				(sheetname "")
			)
			(fill
				(thermal_gap 0.5)
				(thermal_bridge_width 0.5)
				(island_removal_mode 0)
			)
			(polygon
				(pts
					(xy 414.380172 -48.337978) (xy 413.872172 -48.337978) (xy 413.872172 -48.718978) (xy 414.380172 -48.718978)
				)
			)
		)
	)
	(footprint ""
		(layer "F.Cu")
		(at 169.926 -86.868 180)
		(property "Reference" "R4D5"
			(at 0 0 180)
			(layer "F.SilkS")
			(hide yes)
			(effects
				(font
					(size 1.27 1.27)
				)
			)
		)
		(property "Value" ""
			(at 0 0 180)
			(layer "F.Fab")
			(effects
				(font
					(size 1.27 1.27)
				)
			)
		)
		(duplicate_pad_numbers_are_jumpers no)
		(fp_poly
			(pts
				(xy -0.2794 -0.1016) (xy 0.2794 -0.1016) (xy 0.2794 0.9906) (xy -0.2794 0.9906)
			)
			(stroke
				(width 0)
				(type default)
			)
			(fill no)
			(layer "F.CrtYd")
		)
		(fp_line
			(start 0.2794 0.9906)
			(end 0.2794 -0.1016)
			(stroke
				(width 0.1)
				(type default)
			)
			(layer "F.Fab")
		)
		(fp_line
			(start 0.2794 -0.1016)
			(end -0.2794 -0.1016)
			(stroke
				(width 0.1)
				(type default)
			)
			(layer "F.Fab")
		)
		(fp_line
			(start -0.2794 0.9906)
			(end 0.2794 0.9906)
			(stroke
				(width 0.1)
				(type default)
			)
			(layer "F.Fab")
		)
		(fp_line
			(start -0.2794 -0.1016)
			(end -0.2794 0.9906)
			(stroke
				(width 0.1)
				(type default)
			)
			(layer "F.Fab")
		)
		(pad "1" smd rect
			(at 0 0 180)
			(size 0.508 0.508)
			(layers "F.Cu" "F.Mask" "F.Paste")
			(net "CLK_100M_CPU0_RC_REFCLK1_R_DN")
		)
		(pad "2" smd rect
			(at 0 0.889 180)
			(size 0.508 0.508)
			(layers "F.Cu" "F.Mask" "F.Paste")
			(net "CLK_100M_CPU0_RC_REFCLK1_DN")
		)
		(zone
			(layer "F.Cu")
			(hatch none 0.5)
			(connect_pads
				(clearance 0)
			)
			(min_thickness 0.25)
			(keepout
				(tracks not_allowed)
				(vias allowed)
				(pads allowed)
				(copperpour not_allowed)
				(footprints allowed)
			)
			(placement
				(enabled no)
				(sheetname "")
			)
			(fill
				(thermal_gap 0.5)
				(thermal_bridge_width 0.5)
				(island_removal_mode 0)
			)
			(polygon
				(pts
					(xy 170.18 -87.503) (xy 169.672 -87.503) (xy 169.672 -87.122) (xy 170.18 -87.122)
				)
			)
		)
		(zone
			(layer "F.Cu")
			(hatch none 0.5)
			(connect_pads
				(clearance 0)
			)
			(min_thickness 0.25)
			(keepout
				(tracks allowed)
				(vias not_allowed)
				(pads allowed)
				(copperpour not_allowed)
				(footprints allowed)
			)
			(placement
				(enabled no)
				(sheetname "")
			)
			(fill
				(thermal_gap 0.5)
				(thermal_bridge_width 0.5)
				(island_removal_mode 0)
			)
			(polygon
				(pts
					(xy 170.18 -87.122) (xy 169.672 -87.122) (xy 169.672 -87.503) (xy 170.18 -87.503)
				)
			)
		)
	)
)
